#ISCELL
  mstr_misc prelim *
  *
#ISCELL
  mstr_symbols design_note *
  *
#ISCELL
  mstr_symbols intel_corp_bpage *
  *
#ISCELL
  mstr_standard tap *
  page31_i10
#ISCELL
  mstr_standard tap *
  page31_i100
#ISCELL
  mstr_standard tap *
  page31_i101
#ISCELL
  mstr_standard tap *
  page31_i102
#ISCELL
  mstr_standard tap *
  page31_i103
#ISCELL
  mstr_standard offpage *
  page31_i104
#ISCELL
  mstr_standard offpage *
  page31_i105
#CELL
  chpset_lib skx_ext_b *
  page31_i106
#ISCELL
  mstr_standard tap *
  page31_i11
#ISCELL
  mstr_standard tap *
  page31_i12
#ISCELL
  mstr_standard tap *
  page31_i13
#ISCELL
  mstr_standard tap *
  page31_i14
#ISCELL
  mstr_standard tap *
  page31_i15
#ISCELL
  mstr_standard tap *
  page31_i16
#ISCELL
  mstr_standard tap *
  page31_i17
#ISCELL
  mstr_standard tap *
  page31_i18
#ISCELL
  mstr_standard tap *
  page31_i19
#ISCELL
  mstr_standard tap *
  page31_i3
#ISCELL
  mstr_standard tap *
  page31_i36
#ISCELL
  mstr_standard tap *
  page31_i37
#ISCELL
  mstr_standard tap *
  page31_i38
#ISCELL
  mstr_standard tap *
  page31_i39
#ISCELL
  mstr_standard tap *
  page31_i4
#ISCELL
  mstr_standard tap *
  page31_i40
#ISCELL
  mstr_standard tap *
  page31_i41
#ISCELL
  mstr_standard tap *
  page31_i42
#ISCELL
  mstr_standard tap *
  page31_i43
#ISCELL
  mstr_standard tap *
  page31_i44
#ISCELL
  mstr_standard tap *
  page31_i45
#ISCELL
  mstr_standard tap *
  page31_i46
#ISCELL
  mstr_standard tap *
  page31_i47
#ISCELL
  mstr_standard tap *
  page31_i48
#ISCELL
  mstr_standard tap *
  page31_i49
#ISCELL
  mstr_standard tap *
  page31_i5
#ISCELL
  mstr_standard tap *
  page31_i50
#ISCELL
  mstr_standard tap *
  page31_i51
#ISCELL
  mstr_standard tap *
  page31_i6
#ISCELL
  mstr_standard tap *
  page31_i7
#ISCELL
  mstr_standard offpage *
  page31_i70
#ISCELL
  mstr_standard offpage *
  page31_i71
#ISCELL
  mstr_standard tap *
  page31_i72
#ISCELL
  mstr_standard tap *
  page31_i73
#ISCELL
  mstr_standard tap *
  page31_i74
#ISCELL
  mstr_standard tap *
  page31_i75
#ISCELL
  mstr_standard tap *
  page31_i76
#ISCELL
  mstr_standard tap *
  page31_i77
#ISCELL
  mstr_standard tap *
  page31_i78
#ISCELL
  mstr_standard tap *
  page31_i79
#ISCELL
  mstr_standard tap *
  page31_i80
#ISCELL
  mstr_standard tap *
  page31_i81
#ISCELL
  mstr_standard tap *
  page31_i82
#ISCELL
  mstr_standard tap *
  page31_i83
#ISCELL
  mstr_standard tap *
  page31_i84
#ISCELL
  mstr_standard tap *
  page31_i85
#ISCELL
  mstr_standard tap *
  page31_i86
#ISCELL
  mstr_standard tap *
  page31_i87
#ISCELL
  mstr_standard tap *
  page31_i88
#ISCELL
  mstr_standard tap *
  page31_i89
#ISCELL
  mstr_standard tap *
  page31_i9
#ISCELL
  mstr_standard tap *
  page31_i90
#ISCELL
  mstr_standard tap *
  page31_i91
#ISCELL
  mstr_standard tap *
  page31_i92
#ISCELL
  mstr_standard tap *
  page31_i93
#ISCELL
  mstr_standard tap *
  page31_i94
#ISCELL
  mstr_standard tap *
  page31_i95
#ISCELL
  mstr_standard tap *
  page31_i96
#ISCELL
  mstr_standard tap *
  page31_i97
#ISCELL
  mstr_standard tap *
  page31_i98
#ISCELL
  mstr_standard tap *
  page31_i99
